# T6G (Grand Teton) — schematic parts with pin connectivity, parts 2607–2607 of 8303; source: Cadence DE-HDL packaged netlist (pstxprt.dat, pstxnet.dat, pstchip.dat)

J27  SCONN288_DDR506112002KQ  IO  pkg DDR288S_1-1VXC  page 105
  1  VIN_BULK0  POWER  = P12V_MEM_CPU1
  2  RFU0  TRI  = NC
  3  VIN_MGMT  POWER  = P3V3_AUX
  4  HSCL  IN  = I3C_SPD_DDRH_CPU1_SCL
  5  HSDA  BI  = I3C_SPD_DDRH_CPU1_SDA
  6  VSS0  POWER  = GND
  7  DQ0_A  BI  = M_H_CPU1_SA_DQ<0>
  8  VSS1  POWER  = GND
  9  DQ1_A  BI  = M_H_CPU1_SA_DQ<1>
  10  VSS2  POWER  = GND
  11  DQS0_A_T  BI  = M_H_CPU1_SA_DQS_DP<0>
  12  DQS0_A_C  BI  = M_H_CPU1_SA_DQS_DN<0>
  13  VSS3  POWER  = GND
  14  DQ4_A  BI  = M_H_CPU1_SA_DQ<4>
  15  VSS4  POWER  = GND
  16  DQ5_A  BI  = M_H_CPU1_SA_DQ<5>
  17  VSS5  POWER  = GND
  18  DQ8_A  BI  = M_H_CPU1_SA_DQ<8>
  19  VSS6  POWER  = GND
  20  DQ9_A  BI  = M_H_CPU1_SA_DQ<9>
  21  VSS7  POWER  = GND
  22  DQS1_A_T  BI  = M_H_CPU1_SA_DQS_DP<1>
  23  DQS1_A_C  BI  = M_H_CPU1_SA_DQS_DN<1>
  24  VSS8  POWER  = GND
  25  DQ12_A  BI  = M_H_CPU1_SA_DQ<12>
  26  VSS9  POWER  = GND
  27  DQ13_A  BI  = M_H_CPU1_SA_DQ<13>
  28  VSS10  POWER  = GND
  29  DQ16_A  BI  = M_H_CPU1_SA_DQ<16>
  30  VSS11  POWER  = GND
  31  DQ17_A  BI  = M_H_CPU1_SA_DQ<17>
  32  VSS12  POWER  = GND
  33  DQS2_A_T  BI  = M_H_CPU1_SA_DQS_DP<2>
  34  DQS2_A_C  BI  = M_H_CPU1_SA_DQS_DN<2>
  35  VSS13  POWER  = GND
  36  DQ20_A  BI  = M_H_CPU1_SA_DQ<20>
  37  VSS14  POWER  = GND
  38  DQ21_A  BI  = M_H_CPU1_SA_DQ<21>
  39  VSS15  POWER  = GND
  40  DQ24_A  BI  = M_H_CPU1_SA_DQ<24>
  41  VSS16  POWER  = GND
  42  DQ25_A  BI  = M_H_CPU1_SA_DQ<25>
  43  VSS17  POWER  = GND
  44  DQS3_A_T  BI  = M_H_CPU1_SA_DQS_DP<3>
  45  DQS3_A_C  BI  = M_H_CPU1_SA_DQS_DN<3>
  46  VSS18  POWER  = GND
  47  DQ28_A  BI  = M_H_CPU1_SA_DQ<28>
  48  VSS19  POWER  = GND
  49  DQ29_A  BI  = M_H_CPU1_SA_DQ<29>
  50  VSS20  POWER  = GND
  51  CB0_A  BI  = M_H_CPU1_SA_CB<0>
  52  VSS21  POWER  = GND
  53  CB1_A  BI  = M_H_CPU1_SA_CB<1>
  54  VSS22  POWER  = GND
  55  DQS4_A_T  BI  = M_H_CPU1_SA_DQS_DP<4>
  56  DQS4_A_C  BI  = M_H_CPU1_SA_DQS_DN<4>
  57  VSS23  POWER  = GND
  58  CB4_A  BI  = M_H_CPU1_SA_CB<4>
  59  VSS24  POWER  = GND
  60  CB5_A  BI  = M_H_CPU1_SA_CB<5>
  61  VSS25  POWER  = GND
  62  ALERT_N  OUT  = M_H_CPU1_ALERT_N
  63  VSS26  POWER  = GND
  64  CS0_A_N  IN  = M_H_CPU1_SA_CS_N<0>
  65  VSS27  POWER  = GND
  66  CA0_A  IN  = M_H_CPU1_SA_CA<0>
  67  VSS28  POWER  = GND
  68  CA2_A  IN  = M_H_CPU1_SA_CA<2>
  69  VSS29  POWER  = GND
  70  CA4_A  IN  = M_H_CPU1_SA_CA<4>
  71  VSS30  POWER  = GND
  72  CA6_A  IN  = M_H_CPU1_SA_CA<6>
  73  VSS31  POWER  = GND
  74  PAR_A  IN  = M_H_CPU1_SA_PAR
  75  VSS32  POWER  = GND
  76  CA0_B  IN  = M_H_CPU1_SB_CA<0>
  77  VSS33  POWER  = GND
  78  CA2_B  IN  = M_H_CPU1_SB_CA<2>
  79  VSS34  POWER  = GND
  80  CA4_B  IN  = M_H_CPU1_SB_CA<4>
  81  VSS35  POWER  = GND
  82  CA6_B  IN  = M_H_CPU1_SB_CA<6>
  83  VSS36  POWER  = GND
  84  CS0_B_N  IN  = M_H_CPU1_SB_CS_N<0>
  85  VSS37  POWER  = GND
  86  \lbd||rsp_a_n\  OUT  = M_H_CPU1_SA_RSP<0>
  87  \lbs||rsp_b_n\  OUT  = M_H_CPU1_SB_RSP<0>
  88  VSS38  POWER  = GND
  89  CB4_B  BI  = M_H_CPU1_SB_CB<4>
  90  VSS39  POWER  = GND
  91  CB5_B  BI  = M_H_CPU1_SB_CB<5>
  92  VSS40  POWER  = GND
  93  \dqs9_b_t||tdqs9_b_t||dbi4_b_n\  BI  = M_H_CPU1_SB_DQS_DP<9>
  94  \dqs9_b_c||tdqs9_b_c\  BI  = M_H_CPU1_SB_DQS_DN<9>
  95  VSS41  POWER  = GND
  96  CB0_B  BI  = M_H_CPU1_SB_CB<0>
  97  VSS42  POWER  = GND
  98  CB1_B  BI  = M_H_CPU1_SB_CB<1>
  99  VSS43  POWER  = GND
  100  DQ0_B  BI  = M_H_CPU1_SB_DQ<0>
  101  VSS44  POWER  = GND
  102  DQ1_B  BI  = M_H_CPU1_SB_DQ<1>
  103  VSS45  POWER  = GND
  104  DQS0_B_T  BI  = M_H_CPU1_SB_DQS_DP<0>
  105  DQS0_B_C  BI  = M_H_CPU1_SB_DQS_DN<0>
  106  VSS46  POWER  = GND
  107  DQ4_B  BI  = M_H_CPU1_SB_DQ<4>
  108  VSS47  POWER  = GND
  109  DQ5_B  BI  = M_H_CPU1_SB_DQ<5>
  110  VSS48  POWER  = GND
  111  DQ8_B  BI  = M_H_CPU1_SB_DQ<8>
  112  VSS49  POWER  = GND
  113  DQ9_B  BI  = M_H_CPU1_SB_DQ<9>
  114  VSS50  POWER  = GND
  115  DQS1_B_T  BI  = M_H_CPU1_SB_DQS_DP<1>
  116  DQS1_B_C  BI  = M_H_CPU1_SB_DQS_DN<1>
  117  VSS51  POWER  = GND
  118  DQ12_B  BI  = M_H_CPU1_SB_DQ<12>
  119  VSS52  POWER  = GND
  120  DQ13_B  BI  = M_H_CPU1_SB_DQ<13>
  121  VSS53  POWER  = GND
  122  DQ16_B  BI  = M_H_CPU1_SB_DQ<16>
  123  VSS54  POWER  = GND
  124  DQ17_B  BI  = M_H_CPU1_SB_DQ<17>
  125  VSS55  POWER  = GND
  126  DQS2_B_T  BI  = M_H_CPU1_SB_DQS_DP<2>
  127  DQS2_B_C  BI  = M_H_CPU1_SB_DQS_DN<2>
  128  VSS56  POWER  = GND
  129  DQ20_B  BI  = M_H_CPU1_SB_DQ<20>
  130  VSS57  POWER  = GND
  131  DQ21_B  BI  = M_H_CPU1_SB_DQ<21>
  132  VSS58  POWER  = GND
  133  DQ24_B  BI  = M_H_CPU1_SB_DQ<24>
  134  VSS59  POWER  = GND
  135  DQ25_B  BI  = M_H_CPU1_SB_DQ<25>
  136  VSS60  POWER  = GND
  137  DQS3_B_T  BI  = M_H_CPU1_SB_DQS_DP<3>
  138  DQS3_B_C  BI  = M_H_CPU1_SB_DQS_DN<3>
  139  VSS61  POWER  = GND
  140  DQ28_B  BI  = M_H_CPU1_SB_DQ<28>
  141  VSS62  POWER  = GND
  142  DQ29_B  BI  = M_H_CPU1_SB_DQ<29>
  143  VSS63  POWER  = GND
  144  RFU1  TRI  = NC
  145  VIN_BULK1  POWER  = P12V_MEM_CPU1
  146  VIN_BULK2  POWER  = P12V_MEM_CPU1
  147  \pwr_good||fail_n\  BI  = PWRGD_CHH_CPU1_DIMM
  148  HAS  IN  = PD_CHH_CPU1_DIMM_SAA
  149  RFU2  TRI  = NC
  150  RFU3  TRI  = NC
  151  VSS64  POWER  = GND
  152  DQ2_A  BI  = M_H_CPU1_SA_DQ<2>
  153  VSS65  POWER  = GND
  154  DQ3_A  BI  = M_H_CPU1_SA_DQ<3>
  155  VSS66  POWER  = GND
  156  \dqs5_a_c||tdqs5_a_c||dqs5_a_t||tdqs5_a_t\  BI  = M_H_CPU1_SA_DQS_DN<5>
  157  \dqs5_a_t||tdqs5_a_t\  BI  = M_H_CPU1_SA_DQS_DP<5>
  158  VSS67  POWER  = GND
  159  DQ6_A  BI  = M_H_CPU1_SA_DQ<6>
  160  VSS68  POWER  = GND
  161  DQ7_A  BI  = M_H_CPU1_SA_DQ<7>
  162  VSS69  POWER  = GND
  163  DQ10_A  BI  = M_H_CPU1_SA_DQ<10>
  164  VSS70  POWER  = GND
  165  DQ11_A  BI  = M_H_CPU1_SA_DQ<11>
  166  VSS71  POWER  = GND
  167  \dqs6_a_c||tdqs6_a_c||dqs6_a_t||tdqs6_a_t\  BI  = M_H_CPU1_SA_DQS_DN<6>
  168  \dqs6_a_t||tdqs6_a_t\  BI  = M_H_CPU1_SA_DQS_DP<6>
  169  VSS72  POWER  = GND
  170  DQ14_A  BI  = M_H_CPU1_SA_DQ<14>
  171  VSS73  POWER  = GND
  172  DQ15_A  BI  = M_H_CPU1_SA_DQ<15>
  173  VSS74  POWER  = GND
  174  DQ18_A  BI  = M_H_CPU1_SA_DQ<18>
  175  VSS75  POWER  = GND
  176  DQ19_A  BI  = M_H_CPU1_SA_DQ<19>
  177  VSS76  POWER  = GND
  178  \dqs7_a_c||tdqs7_a_c\  BI  = M_H_CPU1_SA_DQS_DN<7>
  179  \dqs7_a_t||tdqs7_a_t\  BI  = M_H_CPU1_SA_DQS_DP<7>
  180  VSS77  POWER  = GND
  181  DQ22_A  BI  = M_H_CPU1_SA_DQ<22>
  182  VSS78  POWER  = GND
  183  DQ23_A  BI  = M_H_CPU1_SA_DQ<23>
  184  VSS79  POWER  = GND
  185  DQ26_A  BI  = M_H_CPU1_SA_DQ<26>
  186  VSS80  POWER  = GND
  187  DQ27_A  BI  = M_H_CPU1_SA_DQ<27>
  188  VSS81  POWER  = GND
  189  \dqs8_a_c||tdqs8_a_c\  BI  = M_H_CPU1_SA_DQS_DN<8>
  190  \dqs8_a_t||tdqs8_a_t\  BI  = M_H_CPU1_SA_DQS_DP<8>
  191  VSS82  POWER  = GND
  192  DQ30_A  BI  = M_H_CPU1_SA_DQ<30>
  193  VSS83  POWER  = GND
  194  DQ31_A  BI  = M_H_CPU1_SA_DQ<31>
  195  VSS84  POWER  = GND
  196  CB2_A  BI  = M_H_CPU1_SA_CB<2>
  197  VSS85  POWER  = GND
  198  CB3_A  BI  = M_H_CPU1_SA_CB<3>
  199  VSS86  POWER  = GND
  200  \dqs9_a_c||tdqs9_a_c\  BI  = M_H_CPU1_SA_DQS_DN<9>
  201  \dqs9_a_t||tdqs9_a_t\  BI  = M_H_CPU1_SA_DQS_DP<9>
  202  VSS87  POWER  = GND
  203  CB6_A  BI  = M_H_CPU1_SA_CB<6>
  204  VSS88  POWER  = GND
  205  CB7_A  BI  = M_H_CPU1_SA_CB<7>
  206  VSS89  POWER  = GND
  207  RESET_N  IN  = M_H_CPU1_RESET_N
  208  VSS90  POWER  = GND
  209  CS1_A_N  IN  = M_H_CPU1_SA_CS_N<1>
  210  VSS91  POWER  = GND
  211  CA1_A  IN  = M_H_CPU1_SA_CA<1>
  212  VSS92  POWER  = GND
  213  CA3_A  IN  = M_H_CPU1_SA_CA<3>
  214  VSS93  POWER  = GND
  215  CA5_A  IN  = M_H_CPU1_SA_CA<5>
  216  VSS94  POWER  = GND
  217  CK_T  IN  = M_H_CPU1_CLK_DP<0>
  218  CK_C  IN  = M_H_CPU1_CLK_DN<0>
  219  VSS95  POWER  = GND
  220  RFU4  TRI  = NC
  221  CA1_B  IN  = M_H_CPU1_SB_CA<1>
  222  VSS96  POWER  = GND
  223  CA3_B  IN  = M_H_CPU1_SB_CA<3>
  224  VSS97  POWER  = GND
  225  CA5_B  IN  = M_H_CPU1_SB_CA<5>
  226  VSS98  POWER  = GND
  227  PAR_B  IN  = M_H_CPU1_SB_PAR
  228  VSS99  POWER  = GND
  229  CS1_B_N  IN  = M_H_CPU1_SB_CS_N<1>
  230  VSS100  POWER  = GND
  231  RFU5  TRI  = NC
  232  RFU6  TRI  = NC
  233  VSS101  POWER  = GND
  234  CB6_B  BI  = M_H_CPU1_SB_CB<6>
  235  VSS102  POWER  = GND
  236  CB7_B  BI  = M_H_CPU1_SB_CB<7>
  237  VSS103  POWER  = GND
  238  DQS4_B_C  BI  = M_H_CPU1_SB_DQS_DN<4>
  239  DQS4_B_T  BI  = M_H_CPU1_SB_DQS_DP<4>
  240  VSS104  POWER  = GND
  241  CB2_B  BI  = M_H_CPU1_SB_CB<2>
  242  VSS105  POWER  = GND
  243  CB3_B  BI  = M_H_CPU1_SB_CB<3>
  244  VSS106  POWER  = GND
  245  DQ2_B  BI  = M_H_CPU1_SB_DQ<2>
  246  VSS107  POWER  = GND
  247  DQ3_B  BI  = M_H_CPU1_SB_DQ<3>
  248  VSS108  POWER  = GND
  249  \dqs5_b_c||tdqs5_b_c\  BI  = M_H_CPU1_SB_DQS_DN<5>
  250  \dqs5_b_t||tdqs5_b_t\  BI  = M_H_CPU1_SB_DQS_DP<5>
  251  VSS109  POWER  = GND
  252  DQ6_B  BI  = M_H_CPU1_SB_DQ<6>
  253  VSS110  POWER  = GND
  254  DQ7_B  BI  = M_H_CPU1_SB_DQ<7>
  255  VSS111  POWER  = GND
  256  DQ10_B  BI  = M_H_CPU1_SB_DQ<10>
  257  VSS112  POWER  = GND
  258  DQ11_B  BI  = M_H_CPU1_SB_DQ<11>
  259  VSS113  POWER  = GND
  260  \dqs6_b_c||tdqs6_b_c\  BI  = M_H_CPU1_SB_DQS_DN<6>
  261  \dqs6_b_t||tdqs6_b_t\  BI  = M_H_CPU1_SB_DQS_DP<6>
  262  VSS114  POWER  = GND
  263  DQ14_B  BI  = M_H_CPU1_SB_DQ<14>
  264  VSS115  POWER  = GND
  265  DQ15_B  BI  = M_H_CPU1_SB_DQ<15>
  266  VSS116  POWER  = GND
  267  DQ18_B  BI  = M_H_CPU1_SB_DQ<18>
  268  VSS117  POWER  = GND
  269  DQ19_B  BI  = M_H_CPU1_SB_DQ<19>
  270  VSS118  POWER  = GND
  271  \dqs7_b_c||tdqs7_b_c\  BI  = M_H_CPU1_SB_DQS_DN<7>
  272  \dqs7_b_t||tdqs7_b_t\  BI  = M_H_CPU1_SB_DQS_DP<7>
  273  VSS119  POWER  = GND
  274  DQ22_B  BI  = M_H_CPU1_SB_DQ<22>
  275  VSS120  POWER  = GND
  276  DQ23_B  BI  = M_H_CPU1_SB_DQ<23>
  277  VSS121  POWER  = GND
  278  DQ26_B  BI  = M_H_CPU1_SB_DQ<26>
  279  VSS122  POWER  = GND
  280  DQ27_B  BI  = M_H_CPU1_SB_DQ<27>
  281  VSS123  POWER  = GND
  282  \dqs8_b_c||tdqs8_b_c\  BI  = M_H_CPU1_SB_DQS_DN<8>
  283  \dqs8_b_t||tdqs8_b_t\  BI  = M_H_CPU1_SB_DQS_DP<8>
  284  VSS124  POWER  = GND
  285  DQ30_B  BI  = M_H_CPU1_SB_DQ<30>
  286  VSS125  POWER  = GND
  287  DQ31_B  BI  = M_H_CPU1_SB_DQ<31>
  288  VSS126  POWER  = GND
  G1  G1  POWER  = GND
  G2  G2  POWER  = GND
  G3  G3  POWER  = GND
